FILE_TYPE = CONNECTIVITY;
{Allegro Design Entry HDL 17.2-2016 S081 (4005846) 1/11/2022}
"PAGE_NUMBER" = 38;
0"NC";
1"M_B_CPU1_SA_DQ<31:0>";
2"M_B_CPU1_SB_DQ<31:0>";
3"M_B_CPU1_SA_CB<7:0>";
4"M_B_CPU1_SB_CB<7:0>";
5"M_B_CPU1_SA_DQS_DP<9:0>";
6"M_B_CPU1_SB_DQS_DP<9:0>";
7"M_B_CPU1_SA_CA<6:0>";
8"M_B_CPU1_SB_CA<6:0>";
9"M_B_CPU1_SA_DQS_DN<9:0>";
10"M_B_CPU1_SB_DQS_DN<9:0>";
11"M_B_CPU1_ALERT_N";
12"TP_M_B_CPU1_SA_TEST39B";
13"M_B_CPU1_ALERT_R_N";
14"M_B_CPU1_CLK_DP<0>";
15"M_B_CPU1_CLK_DN<0>";
16"M_B_CPU1_SA_CS_N<0>";
17"M_B_CPU1_SA_CS_N<1>";
18"M_B_CPU1_SA_RSP<0>";
19"M_B_CPU1_SA_PAR";
20"M_B_CPU1_SB_CS_N<1>";
21"M_B_CPU1_SB_CS_N<0>";
22"M_B_CPU1_SB_RSP<0>";
23"M_B_CPU1_SB_PAR";
24"M_B_CPU1_RESET_N";
25"M_B_CPU1_SB_DQS_DP<9>";
26"M_B_CPU1_SB_CA<6>";
27"M_B_CPU1_SA_CA<6>";
28"M_B_CPU1_SB_CA<5>";
29"M_B_CPU1_SA_CA<5>";
30"M_B_CPU1_SB_CA<4>";
31"M_B_CPU1_SA_CA<4>";
32"M_B_CPU1_SB_CA<3>";
33"M_B_CPU1_SA_CA<3>";
34"M_B_CPU1_SB_CA<2>";
35"M_B_CPU1_SA_CA<2>";
36"M_B_CPU1_SB_CA<1>";
37"M_B_CPU1_SA_CA<1>";
38"M_B_CPU1_SB_CA<0>";
39"M_B_CPU1_SA_CA<0>";
40"M_B_CPU1_SB_DQS_DN<9>";
41"M_B_CPU1_SB_DQS_DP<4>";
42"M_B_CPU1_SB_DQS_DN<8>";
43"M_B_CPU1_SB_DQS_DP<3>";
44"M_B_CPU1_SB_DQS_DN<7>";
45"M_B_CPU1_SB_DQS_DP<2>";
46"M_B_CPU1_SB_DQS_DN<6>";
47"M_B_CPU1_SB_DQS_DP<1>";
48"M_B_CPU1_SB_DQS_DN<5>";
49"M_B_CPU1_SB_DQS_DP<0>";
50"M_B_CPU1_SB_DQS_DN<4>";
51"M_B_CPU1_SA_DQS_DN<9>";
52"M_B_CPU1_SB_DQS_DN<3>";
53"M_B_CPU1_SB_DQS_DN<2>";
54"M_B_CPU1_SB_DQS_DN<1>";
55"M_B_CPU1_SB_DQS_DN<0>";
56"M_B_CPU1_SB_DQS_DP<8>";
57"M_B_CPU1_SB_DQS_DP<7>";
58"M_B_CPU1_SB_DQS_DP<6>";
59"M_B_CPU1_SB_DQS_DP<5>";
60"M_B_CPU1_SA_DQS_DP<9>";
61"M_B_CPU1_SA_DQS_DP<8>";
62"M_B_CPU1_SA_DQS_DP<7>";
63"M_B_CPU1_SA_DQS_DP<6>";
64"M_B_CPU1_SA_DQS_DP<5>";
65"M_B_CPU1_SA_DQS_DP<4>";
66"M_B_CPU1_SA_DQS_DN<8>";
67"M_B_CPU1_SA_DQS_DP<3>";
68"M_B_CPU1_SA_DQS_DN<7>";
69"M_B_CPU1_SA_DQS_DP<2>";
70"M_B_CPU1_SA_DQS_DN<6>";
71"M_B_CPU1_SA_DQS_DP<1>";
72"M_B_CPU1_SA_DQS_DN<5>";
73"M_B_CPU1_SA_DQS_DP<0>";
74"M_B_CPU1_SA_DQS_DN<4>";
75"M_B_CPU1_SA_DQS_DN<3>";
76"M_B_CPU1_SA_DQS_DN<2>";
77"M_B_CPU1_SA_DQS_DN<1>";
78"M_B_CPU1_SA_DQS_DN<0>";
79"M_B_CPU1_SB_CB<7>";
80"M_B_CPU1_SB_CB<6>";
81"M_B_CPU1_SB_CB<5>";
82"M_B_CPU1_SB_CB<4>";
83"M_B_CPU1_SB_CB<3>";
84"M_B_CPU1_SB_CB<2>";
85"M_B_CPU1_SB_CB<1>";
86"M_B_CPU1_SB_CB<0>";
87"M_B_CPU1_SA_CB<1>";
88"M_B_CPU1_SA_CB<0>";
89"M_B_CPU1_SB_DQ<29>";
90"M_B_CPU1_SB_DQ<28>";
91"M_B_CPU1_SB_DQ<27>";
92"M_B_CPU1_SB_DQ<26>";
93"M_B_CPU1_SB_DQ<25>";
94"M_B_CPU1_SB_DQ<24>";
95"M_B_CPU1_SB_DQ<23>";
96"M_B_CPU1_SB_DQ<22>";
97"M_B_CPU1_SA_CB<7>";
98"M_B_CPU1_SA_CB<6>";
99"M_B_CPU1_SB_DQ<31>";
100"M_B_CPU1_SA_CB<5>";
101"M_B_CPU1_SB_DQ<30>";
102"M_B_CPU1_SA_CB<4>";
103"M_B_CPU1_SA_CB<3>";
104"M_B_CPU1_SA_CB<2>";
105"M_B_CPU1_SB_DQ<20>";
106"M_B_CPU1_SB_DQ<19>";
107"M_B_CPU1_SB_DQ<18>";
108"M_B_CPU1_SB_DQ<9>";
109"M_B_CPU1_SB_DQ<17>";
110"M_B_CPU1_SB_DQ<8>";
111"M_B_CPU1_SB_DQ<16>";
112"M_B_CPU1_SB_DQ<7>";
113"M_B_CPU1_SB_DQ<15>";
114"M_B_CPU1_SB_DQ<6>";
115"M_B_CPU1_SB_DQ<14>";
116"M_B_CPU1_SB_DQ<5>";
117"M_B_CPU1_SB_DQ<13>";
118"M_B_CPU1_SB_DQ<4>";
119"M_B_CPU1_SB_DQ<12>";
120"M_B_CPU1_SB_DQ<3>";
121"M_B_CPU1_SB_DQ<11>";
122"M_B_CPU1_SB_DQ<10>";
123"M_B_CPU1_SB_DQ<21>";
124"M_B_CPU1_SA_DQ<24>";
125"M_B_CPU1_SA_DQ<21>";
126"M_B_CPU1_SA_DQ<20>";
127"M_B_CPU1_SA_DQ<31>";
128"M_B_CPU1_SA_DQ<30>";
129"M_B_CPU1_SA_DQ<19>";
130"M_B_CPU1_SA_DQ<18>";
131"M_B_CPU1_SA_DQ<29>";
132"M_B_CPU1_SA_DQ<17>";
133"M_B_CPU1_SA_DQ<28>";
134"M_B_CPU1_SA_DQ<27>";
135"M_B_CPU1_SB_DQ<2>";
136"M_B_CPU1_SA_DQ<26>";
137"M_B_CPU1_SB_DQ<1>";
138"M_B_CPU1_SA_DQ<25>";
139"M_B_CPU1_SB_DQ<0>";
140"M_B_CPU1_SA_DQ<23>";
141"M_B_CPU1_SA_DQ<22>";
142"M_B_CPU1_SA_DQ<10>";
143"M_B_CPU1_SA_DQ<9>";
144"M_B_CPU1_SA_DQ<8>";
145"M_B_CPU1_SA_DQ<7>";
146"M_B_CPU1_SA_DQ<6>";
147"M_B_CPU1_SA_DQ<5>";
148"M_B_CPU1_SA_DQ<4>";
149"M_B_CPU1_SA_DQ<3>";
150"M_B_CPU1_SA_DQ<16>";
151"M_B_CPU1_SA_DQ<2>";
152"M_B_CPU1_SA_DQ<15>";
153"M_B_CPU1_SA_DQ<1>";
154"M_B_CPU1_SA_DQ<14>";
155"M_B_CPU1_SA_DQ<0>";
156"M_B_CPU1_SA_DQ<13>";
157"M_B_CPU1_SA_DQ<12>";
158"M_B_CPU1_SA_DQ<11>";
%"GENOA_SP5"
"2","(-4725,3625)","0","pure_quanta","I159";
;
LOCATION"U26"
$SEC"2"
CDS_SEC"2"
PART_TYPE"SMLF"
MATERIAL"IO"
VALUE"SOCKET6096_13568-001"
PART_NUMBER"DGA^6000030"
CDS_LIB"pure_quanta"
NEEDS_NO_SIZE"TRUE"
CDS_LMAN_SYM_OUTLINE"-650,2550,650,-2550";
"TEST39B"
$PN"BF62"12;
"MBB_DATA20"
$PN"CV63"105;
"MBA_DATA24"
$PN"AC64"124;
"MBB_DATA19"
$PN"CT62"106;
"MB1_CLK_L"
$PN"BG64"0;
"MB1_CLK_H"
$PN"BF63"0;
"MB0_CLK_L"
$PN"BD63"15;
"MB0_CLK_H"
$PN"BC64"14;
"MBB_PAR"
$PN"BL64"23;
"MBA_PAR"
$PN"BC62"19;
"MBB_DQS_H9"
$PN"BV63"25;
"MBA_CHECK1"
$PN"AK62"87;
"MBA_DATA10"
$PN"M63"142;
"MBA_DATA21"
$PN"AB62"125;
"MBB_DQS_H4"
$PN"BY62"41;
"MBB_DQS_L8"
$PN"DC62"42;
"MBA1_CS_L1"
$PN"AV62"0;
"MBA_CHECK0"
$PN"AJ64"88;
"MBA_DATA20"
$PN"AA64"126;
"MBA_DATA31"
$PN"AJ62"127;
"MBA_DQS_H9"
$PN"AN62"60;
"MBB_CA6"
$PN"BK63"26;
"MBB_DQS_H3"
$PN"DB63"43;
"MBB_DQS_L7"
$PN"CU62"44;
"MBA0_CS_L1"
$PN"AW62"17;
"MBA1_CS_L0"
$PN"AU64"0;
"MBA_CA6"
$PN"BB62"27;
"MBA_DATA30"
$PN"AH63"128;
"MBA_DQS_H8"
$PN"AG62"61;
"MBB_CA5"
$PN"BK62"28;
"MBB_DQS_H2"
$PN"CT63"45;
"MBB_DQS_L6"
$PN"CL62"46;
"MBA0_CS_L0"
$PN"AV63"16;
"MBA_CA5"
$PN"BB63"29;
"MBA_DQS_H7"
$PN"AA62"62;
"MBB_CA4"
$PN"BJ62"30;
"MBB_DATA18"
$PN"CR64"107;
"MBB_DATA29"
$PN"DE62"89;
"MBB_DQS_H1"
$PN"CK63"47;
"MBB_DQS_L5"
$PN"CE62"48;
"MBA_CA4"
$PN"BA64"31;
"MBA_DQS_H6"
$PN"R62"63;
"MBB1_RSP_L"
$PN"BR64"0;
"MBB_CA3"
$PN"BJ64"32;
"MBB_DATA9"
$PN"CJ62"108;
"MBB_DATA17"
$PN"CR62"109;
"MBB_DATA28"
$PN"DD63"90;
"MBB_DQS_H0"
$PN"CD63"49;
"MBB_DQS_L4"
$PN"BW62"50;
"MBA_CA3"
$PN"BA62"33;
"MBA_DATA9"
$PN"M62"143;
"MBA_DQS_H5"
$PN"J62"64;
"MBA_DQS_L9"
$PN"AM62"51;
"MBB0_RSP_L"
$PN"BP63"22;
"MBB_CA2"
$PN"BH63"34;
"MBB_CHECK7"
$PN"BV62"79;
"MBB_DATA8"
$PN"CH63"110;
"MBB_DATA16"
$PN"CP63"111;
"MBB_DATA27"
$PN"DB62"91;
"MBB_DQS_L3"
$PN"DC64"52;
"MBA_CA2"
$PN"AY62"35;
"MBA_DATA8"
$PN"L64"144;
"MBA_DQS_H4"
$PN"AL64"65;
"MBA_DQS_L8"
$PN"AF62"66;
"MBB_CA1"
$PN"BH62"36;
"MBB_CHECK6"
$PN"BU64"80;
"MBB_DATA7"
$PN"CH62"112;
"MBB_DATA15"
$PN"CP62"113;
"MBB_DATA26"
$PN"DA64"92;
"MBB_DQS_L2"
$PN"CU64"53;
"MBA_CA1"
$PN"AY63"37;
"MBA_DATA7"
$PN"L62"145;
"MBA_DQS_H3"
$PN"AE64"67;
"MBA_DQS_L7"
$PN"Y62"68;
"MBB_CA0"
$PN"BG62"38;
"MBB_CHECK5"
$PN"BU62"81;
"MBB_DATA6"
$PN"CG64"114;
"MBB_DATA14"
$PN"CN64"115;
"MBB_DATA25"
$PN"DA62"93;
"MBB_DQS_L1"
$PN"CL64"54;
"MBA_CA0"
$PN"AW64"39;
"MBA_DATA6"
$PN"K63"146;
"MBA_DATA19"
$PN"W62"129;
"MBA_DQS_H2"
$PN"W64"69;
"MBA_DQS_L6"
$PN"P62"70;
"MBB_CHECK4"
$PN"BT63"82;
"MBB_DATA5"
$PN"CG62"116;
"MBB_DATA13"
$PN"CN62"117;
"MBB_DATA24"
$PN"CY63"94;
"MBB_DQS_L0"
$PN"CE64"55;
"MBA_DATA5"
$PN"K62"147;
"MBA_DATA18"
$PN"V63"130;
"MBA_DATA29"
$PN"AH62"131;
"MBA_DQS_H1"
$PN"N64"71;
"MBA_DQS_L5"
$PN"H62"72;
"MBB_CHECK3"
$PN"CB62"83;
"MBB_DATA4"
$PN"CF63"118;
"MBB_DATA12"
$PN"CM63"119;
"MBB_DATA23"
$PN"CY62"95;
"MBA1_RSP_L"
$PN"BP62"0;
"MBA_DATA4"
$PN"J64"148;
"MBA_DATA17"
$PN"V62"132;
"MBA_DATA28"
$PN"AG64"133;
"MBA_DQS_H0"
$PN"G64"73;
"MBA_DQS_L4"
$PN"AM63"74;
"MBB_CHECK2"
$PN"CA64"84;
"MBB_DATA3"
$PN"CD62"120;
"MBB_DATA11"
$PN"CK62"121;
"MBB_DATA22"
$PN"CW64"96;
"MBA0_RSP_L"
$PN"BN62"18;
"MBA_CHECK7"
$PN"AR62"97;
"MBA_DATA3"
$PN"G62"149;
"MBA_DATA16"
$PN"U64"150;
"MBA_DATA27"
$PN"AE62"134;
"MBA_DQS_L3"
$PN"AF63"75;
"MBB_CHECK1"
$PN"CA62"85;
"MBB_DATA2"
$PN"CC64"135;
"MBB_DATA10"
$PN"CJ64"122;
"MBB_DATA21"
$PN"CW62"123;
"MBA_CHECK6"
$PN"AP63"98;
"MBA_DATA2"
$PN"F63"151;
"MBA_DATA15"
$PN"U62"152;
"MBA_DATA26"
$PN"AD63"136;
"MBA_DQS_L2"
$PN"Y63"76;
"MBB1_CS_L1"
$PN"BM63"0;
"MBB_CHECK0"
$PN"BY63"86;
"MBB_DATA1"
$PN"CC62"137;
"MBB_DATA31"
$PN"DF62"99;
"MBA_CHECK5"
$PN"AP62"100;
"MBA_DATA1"
$PN"F62"153;
"MBA_DATA14"
$PN"T63"154;
"MBA_DATA25"
$PN"AD62"138;
"MBA_DQS_L1"
$PN"P63"77;
"MBB0_CS_L1"
$PN"BN64"20;
"MBB1_CS_L0"
$PN"BL62"0;
"MBB_DATA0"
$PN"CB63"139;
"MBB_DATA30"
$PN"DE64"101;
"MBB_DQS_H8"
$PN"DD62"56;
"MBA_CHECK4"
$PN"AN64"102;
"MBA_DATA0"
$PN"E64"155;
"MBA_DATA13"
$PN"T62"156;
"MBA_DQS_L0"
$PN"H63"78;
"MBB0_CS_L0"
$PN"BM62"21;
"MBB_DQS_H7"
$PN"CV62"57;
"MBA_CHECK3"
$PN"AL62"103;
"MBA_DATA12"
$PN"R64"157;
"MBA_DATA23"
$PN"AC62"140;
"MBB_DQS_H6"
$PN"CM62"58;
"MBA_CHECK2"
$PN"AK63"104;
"MBA_DATA11"
$PN"N62"158;
"MBA_DATA22"
$PN"AB63"141;
"MBB_DQS_H5"
$PN"CF62"59;
"MBB_DQS_L9"
$PN"BW64"40;
"MB_RESET_L"
$PN"AU62"24;
"MB_ALERT_L"
$PN"AT62"13;
%"TAP"
"1","(-3450,5925)","0","mstr_standard","I162";
;
CDS_LIB"mstr_standard"
BODY_TYPE"PLUMBING"
HDL_TAP"TRUE";
"B \NAC \NWC"1;
"S \NAC"
BN"2"151;
%"TAP"
"1","(-3450,5975)","0","mstr_standard","I163";
;
CDS_LIB"mstr_standard"
BODY_TYPE"PLUMBING"
HDL_TAP"TRUE";
"B \NAC \NWC"1;
"S \NAC"
BN"1"153;
%"TAP"
"1","(-3450,6025)","0","mstr_standard","I164";
;
CDS_LIB"mstr_standard"
BODY_TYPE"PLUMBING"
HDL_TAP"TRUE";
"B \NAC \NWC"1;
"S \NAC"
BN"0"155;
%"TAP"
"1","(-3450,5825)","0","mstr_standard","I165";
;
CDS_LIB"mstr_standard"
BODY_TYPE"PLUMBING"
HDL_TAP"TRUE";
"B \NAC \NWC"1;
"S \NAC"
BN"4"148;
%"TAP"
"1","(-3450,5875)","0","mstr_standard","I166";
;
CDS_LIB"mstr_standard"
BODY_TYPE"PLUMBING"
HDL_TAP"TRUE";
"B \NAC \NWC"1;
"S \NAC"
BN"3"149;
%"TAP"
"1","(-3450,5775)","0","mstr_standard","I167";
;
CDS_LIB"mstr_standard"
BODY_TYPE"PLUMBING"
HDL_TAP"TRUE";
"B \NAC \NWC"1;
"S \NAC"
BN"5"147;
%"TAP"
"1","(-3450,5725)","0","mstr_standard","I168";
;
CDS_LIB"mstr_standard"
BODY_TYPE"PLUMBING"
HDL_TAP"TRUE";
"B \NAC \NWC"1;
"S \NAC"
BN"6"146;
%"TAP"
"1","(-3450,5675)","0","mstr_standard","I169";
;
CDS_LIB"mstr_standard"
BODY_TYPE"PLUMBING"
HDL_TAP"TRUE";
"B \NAC \NWC"1;
"S \NAC"
BN"7"145;
%"TAP"
"1","(-3450,5575)","0","mstr_standard","I170";
;
CDS_LIB"mstr_standard"
BODY_TYPE"PLUMBING"
HDL_TAP"TRUE";
"B \NAC \NWC"1;
"S \NAC"
BN"8"144;
%"TAP"
"1","(-3450,5425)","0","mstr_standard","I171";
;
CDS_LIB"mstr_standard"
BODY_TYPE"PLUMBING"
HDL_TAP"TRUE";
"B \NAC \NWC"1;
"S \NAC"
BN"11"158;
%"TAP"
"1","(-3450,5475)","0","mstr_standard","I172";
;
CDS_LIB"mstr_standard"
BODY_TYPE"PLUMBING"
HDL_TAP"TRUE";
"B \NAC \NWC"1;
"S \NAC"
BN"10"142;
%"TAP"
"1","(-3450,5525)","0","mstr_standard","I173";
;
CDS_LIB"mstr_standard"
BODY_TYPE"PLUMBING"
HDL_TAP"TRUE";
"B \NAC \NWC"1;
"S \NAC"
BN"9"143;
%"TAP"
"1","(-3450,5375)","0","mstr_standard","I174";
;
CDS_LIB"mstr_standard"
BODY_TYPE"PLUMBING"
HDL_TAP"TRUE";
"B \NAC \NWC"1;
"S \NAC"
BN"12"157;
%"TAP"
"1","(-3450,5325)","0","mstr_standard","I175";
;
CDS_LIB"mstr_standard"
BODY_TYPE"PLUMBING"
HDL_TAP"TRUE";
"B \NAC \NWC"1;
"S \NAC"
BN"13"156;
%"TAP"
"1","(-3450,5275)","0","mstr_standard","I176";
;
CDS_LIB"mstr_standard"
BODY_TYPE"PLUMBING"
HDL_TAP"TRUE";
"B \NAC \NWC"1;
"S \NAC"
BN"14"154;
%"TAP"
"1","(-3450,5225)","0","mstr_standard","I177";
;
CDS_LIB"mstr_standard"
BODY_TYPE"PLUMBING"
HDL_TAP"TRUE";
"B \NAC \NWC"1;
"S \NAC"
BN"15"152;
%"TAP"
"1","(-3450,5125)","0","mstr_standard","I178";
;
CDS_LIB"mstr_standard"
BODY_TYPE"PLUMBING"
HDL_TAP"TRUE";
"B \NAC \NWC"1;
"S \NAC"
BN"16"150;
%"TAP"
"1","(-3450,5075)","0","mstr_standard","I179";
;
CDS_LIB"mstr_standard"
BODY_TYPE"PLUMBING"
HDL_TAP"TRUE";
"B \NAC \NWC"1;
"S \NAC"
BN"17"132;
%"TAP"
"1","(-3450,5025)","0","mstr_standard","I180";
;
CDS_LIB"mstr_standard"
BODY_TYPE"PLUMBING"
HDL_TAP"TRUE";
"B \NAC \NWC"1;
"S \NAC"
BN"18"130;
%"TAP"
"1","(-3450,4925)","0","mstr_standard","I181";
;
CDS_LIB"mstr_standard"
BODY_TYPE"PLUMBING"
HDL_TAP"TRUE";
"B \NAC \NWC"1;
"S \NAC"
BN"20"126;
%"TAP"
"1","(-3450,4975)","0","mstr_standard","I182";
;
CDS_LIB"mstr_standard"
BODY_TYPE"PLUMBING"
HDL_TAP"TRUE";
"B \NAC \NWC"1;
"S \NAC"
BN"19"129;
%"TAP"
"1","(-3450,4875)","0","mstr_standard","I183";
;
CDS_LIB"mstr_standard"
BODY_TYPE"PLUMBING"
HDL_TAP"TRUE";
"B \NAC \NWC"1;
"S \NAC"
BN"21"125;
%"TAP"
"1","(-3450,4825)","0","mstr_standard","I184";
;
CDS_LIB"mstr_standard"
BODY_TYPE"PLUMBING"
HDL_TAP"TRUE";
"B \NAC \NWC"1;
"S \NAC"
BN"22"141;
%"TAP"
"1","(-3450,4775)","0","mstr_standard","I185";
;
CDS_LIB"mstr_standard"
BODY_TYPE"PLUMBING"
HDL_TAP"TRUE";
"B \NAC \NWC"1;
"S \NAC"
BN"23"140;
%"TAP"
"1","(-3450,4675)","0","mstr_standard","I186";
;
CDS_LIB"mstr_standard"
BODY_TYPE"PLUMBING"
HDL_TAP"TRUE";
"B \NAC \NWC"1;
"S \NAC"
BN"24"124;
%"TAP"
"1","(-3450,4625)","0","mstr_standard","I187";
;
CDS_LIB"mstr_standard"
BODY_TYPE"PLUMBING"
HDL_TAP"TRUE";
"B \NAC \NWC"1;
"S \NAC"
BN"25"138;
%"TAP"
"1","(-3450,4575)","0","mstr_standard","I188";
;
CDS_LIB"mstr_standard"
BODY_TYPE"PLUMBING"
HDL_TAP"TRUE";
"B \NAC \NWC"1;
"S \NAC"
BN"26"136;
%"TAP"
"1","(-3450,4525)","0","mstr_standard","I189";
;
CDS_LIB"mstr_standard"
BODY_TYPE"PLUMBING"
HDL_TAP"TRUE";
"B \NAC \NWC"1;
"S \NAC"
BN"27"134;
%"TAP"
"1","(-3450,4425)","0","mstr_standard","I190";
;
CDS_LIB"mstr_standard"
BODY_TYPE"PLUMBING"
HDL_TAP"TRUE";
"B \NAC \NWC"1;
"S \NAC"
BN"29"131;
%"TAP"
"1","(-3450,4375)","0","mstr_standard","I191";
;
CDS_LIB"mstr_standard"
BODY_TYPE"PLUMBING"
HDL_TAP"TRUE";
"B \NAC \NWC"1;
"S \NAC"
BN"30"128;
%"TAP"
"1","(-3450,4475)","0","mstr_standard","I192";
;
CDS_LIB"mstr_standard"
BODY_TYPE"PLUMBING"
HDL_TAP"TRUE";
"B \NAC \NWC"1;
"S \NAC"
BN"28"133;
%"TAP"
"1","(-3450,4325)","0","mstr_standard","I193";
;
CDS_LIB"mstr_standard"
BODY_TYPE"PLUMBING"
HDL_TAP"TRUE";
"B \NAC \NWC"1;
"S \NAC"
BN"31"127;
%"TAP"
"1","(-3450,4125)","0","mstr_standard","I194";
;
CDS_LIB"mstr_standard"
BODY_TYPE"PLUMBING"
HDL_TAP"TRUE";
"B \NAC \NWC"2;
"S \NAC"
BN"2"135;
%"TAP"
"1","(-3450,4175)","0","mstr_standard","I195";
;
CDS_LIB"mstr_standard"
BODY_TYPE"PLUMBING"
HDL_TAP"TRUE";
"B \NAC \NWC"2;
"S \NAC"
BN"1"137;
%"TAP"
"1","(-3450,4225)","0","mstr_standard","I196";
;
CDS_LIB"mstr_standard"
BODY_TYPE"PLUMBING"
HDL_TAP"TRUE";
"B \NAC \NWC"2;
"S \NAC"
BN"0"139;
%"TAP"
"1","(-3450,4075)","0","mstr_standard","I198";
;
CDS_LIB"mstr_standard"
BODY_TYPE"PLUMBING"
HDL_TAP"TRUE";
"B \NAC \NWC"2;
"S \NAC"
BN"3"120;
%"TAP"
"1","(-3450,4025)","0","mstr_standard","I199";
;
CDS_LIB"mstr_standard"
BODY_TYPE"PLUMBING"
HDL_TAP"TRUE";
"B \NAC \NWC"2;
"S \NAC"
BN"4"118;
%"TAP"
"1","(-3450,3975)","0","mstr_standard","I200";
;
CDS_LIB"mstr_standard"
BODY_TYPE"PLUMBING"
HDL_TAP"TRUE";
"B \NAC \NWC"2;
"S \NAC"
BN"5"116;
%"TAP"
"1","(-3450,3875)","0","mstr_standard","I201";
;
CDS_LIB"mstr_standard"
BODY_TYPE"PLUMBING"
HDL_TAP"TRUE";
"B \NAC \NWC"2;
"S \NAC"
BN"7"112;
%"TAP"
"1","(-3450,3925)","0","mstr_standard","I202";
;
CDS_LIB"mstr_standard"
BODY_TYPE"PLUMBING"
HDL_TAP"TRUE";
"B \NAC \NWC"2;
"S \NAC"
BN"6"114;
%"TAP"
"1","(-3450,3775)","0","mstr_standard","I203";
;
CDS_LIB"mstr_standard"
BODY_TYPE"PLUMBING"
HDL_TAP"TRUE";
"B \NAC \NWC"2;
"S \NAC"
BN"8"110;
%"TAP"
"1","(-3450,3625)","0","mstr_standard","I204";
;
CDS_LIB"mstr_standard"
BODY_TYPE"PLUMBING"
HDL_TAP"TRUE";
"B \NAC \NWC"2;
"S \NAC"
BN"11"121;
%"TAP"
"1","(-3450,3725)","0","mstr_standard","I205";
;
CDS_LIB"mstr_standard"
BODY_TYPE"PLUMBING"
HDL_TAP"TRUE";
"B \NAC \NWC"2;
"S \NAC"
BN"9"108;
%"TAP"
"1","(-3450,3675)","0","mstr_standard","I206";
;
CDS_LIB"mstr_standard"
BODY_TYPE"PLUMBING"
HDL_TAP"TRUE";
"B \NAC \NWC"2;
"S \NAC"
BN"10"122;
%"TAP"
"1","(-3450,3575)","0","mstr_standard","I207";
;
CDS_LIB"mstr_standard"
BODY_TYPE"PLUMBING"
HDL_TAP"TRUE";
"B \NAC \NWC"2;
"S \NAC"
BN"12"119;
%"TAP"
"1","(-3450,3525)","0","mstr_standard","I208";
;
CDS_LIB"mstr_standard"
BODY_TYPE"PLUMBING"
HDL_TAP"TRUE";
"B \NAC \NWC"2;
"S \NAC"
BN"13"117;
%"TAP"
"1","(-3450,3425)","0","mstr_standard","I209";
;
CDS_LIB"mstr_standard"
BODY_TYPE"PLUMBING"
HDL_TAP"TRUE";
"B \NAC \NWC"2;
"S \NAC"
BN"15"113;
%"TAP"
"1","(-3450,3475)","0","mstr_standard","I210";
;
CDS_LIB"mstr_standard"
BODY_TYPE"PLUMBING"
HDL_TAP"TRUE";
"B \NAC \NWC"2;
"S \NAC"
BN"14"115;
%"TAP"
"1","(-3450,3325)","0","mstr_standard","I211";
;
CDS_LIB"mstr_standard"
BODY_TYPE"PLUMBING"
HDL_TAP"TRUE";
"B \NAC \NWC"2;
"S \NAC"
BN"16"111;
%"TAP"
"1","(-3450,3275)","0","mstr_standard","I212";
;
CDS_LIB"mstr_standard"
BODY_TYPE"PLUMBING"
HDL_TAP"TRUE";
"B \NAC \NWC"2;
"S \NAC"
BN"17"109;
%"TAP"
"1","(-3450,3225)","0","mstr_standard","I213";
;
CDS_LIB"mstr_standard"
BODY_TYPE"PLUMBING"
HDL_TAP"TRUE";
"B \NAC \NWC"2;
"S \NAC"
BN"18"107;
%"TAP"
"1","(-3450,3075)","0","mstr_standard","I214";
;
CDS_LIB"mstr_standard"
BODY_TYPE"PLUMBING"
HDL_TAP"TRUE";
"B \NAC \NWC"2;
"S \NAC"
BN"21"123;
%"TAP"
"1","(-3450,3125)","0","mstr_standard","I215";
;
CDS_LIB"mstr_standard"
BODY_TYPE"PLUMBING"
HDL_TAP"TRUE";
"B \NAC \NWC"2;
"S \NAC"
BN"20"105;
%"TAP"
"1","(-3450,3175)","0","mstr_standard","I216";
;
CDS_LIB"mstr_standard"
BODY_TYPE"PLUMBING"
HDL_TAP"TRUE";
"B \NAC \NWC"2;
"S \NAC"
BN"19"106;
%"TAP"
"1","(-3450,2825)","0","mstr_standard","I217";
;
CDS_LIB"mstr_standard"
BODY_TYPE"PLUMBING"
HDL_TAP"TRUE";
"B \NAC \NWC"2;
"S \NAC"
BN"25"93;
%"TAP"
"1","(-3450,2875)","0","mstr_standard","I218";
;
CDS_LIB"mstr_standard"
BODY_TYPE"PLUMBING"
HDL_TAP"TRUE";
"B \NAC \NWC"2;
"S \NAC"
BN"24"94;
%"TAP"
"1","(-3450,3025)","0","mstr_standard","I219";
;
CDS_LIB"mstr_standard"
BODY_TYPE"PLUMBING"
HDL_TAP"TRUE";
"B \NAC \NWC"2;
"S \NAC"
BN"22"96;
%"TAP"
"1","(-3450,2975)","0","mstr_standard","I220";
;
CDS_LIB"mstr_standard"
BODY_TYPE"PLUMBING"
HDL_TAP"TRUE";
"B \NAC \NWC"2;
"S \NAC"
BN"23"95;
%"TAP"
"1","(-3450,2575)","0","mstr_standard","I221";
;
CDS_LIB"mstr_standard"
BODY_TYPE"PLUMBING"
HDL_TAP"TRUE";
"B \NAC \NWC"2;
"S \NAC"
BN"30"101;
%"TAP"
"1","(-3450,2625)","0","mstr_standard","I222";
;
CDS_LIB"mstr_standard"
BODY_TYPE"PLUMBING"
HDL_TAP"TRUE";
"B \NAC \NWC"2;
"S \NAC"
BN"29"89;
%"TAP"
"1","(-3450,2675)","0","mstr_standard","I223";
;
CDS_LIB"mstr_standard"
BODY_TYPE"PLUMBING"
HDL_TAP"TRUE";
"B \NAC \NWC"2;
"S \NAC"
BN"28"90;
%"TAP"
"1","(-3450,2725)","0","mstr_standard","I224";
;
CDS_LIB"mstr_standard"
BODY_TYPE"PLUMBING"
HDL_TAP"TRUE";
"B \NAC \NWC"2;
"S \NAC"
BN"27"91;
%"TAP"
"1","(-3450,2775)","0","mstr_standard","I225";
;
CDS_LIB"mstr_standard"
BODY_TYPE"PLUMBING"
HDL_TAP"TRUE";
"B \NAC \NWC"2;
"S \NAC"
BN"26"92;
%"TAP"
"1","(-3450,2325)","0","mstr_standard","I226";
;
CDS_LIB"mstr_standard"
BODY_TYPE"PLUMBING"
HDL_TAP"TRUE";
"B \NAC \NWC"3;
"S \NAC"
BN"2"104;
%"TAP"
"1","(-3450,2375)","0","mstr_standard","I227";
;
CDS_LIB"mstr_standard"
BODY_TYPE"PLUMBING"
HDL_TAP"TRUE";
"B \NAC \NWC"3;
"S \NAC"
BN"1"87;
%"TAP"
"1","(-3450,2425)","0","mstr_standard","I228";
;
CDS_LIB"mstr_standard"
BODY_TYPE"PLUMBING"
HDL_TAP"TRUE";
"B \NAC \NWC"3;
"S \NAC"
BN"0"88;
%"TAP"
"1","(-3450,2525)","0","mstr_standard","I229";
;
CDS_LIB"mstr_standard"
BODY_TYPE"PLUMBING"
HDL_TAP"TRUE";
"B \NAC \NWC"2;
"S \NAC"
BN"31"99;
%"TAP"
"1","(-3450,2275)","0","mstr_standard","I230";
;
CDS_LIB"mstr_standard"
BODY_TYPE"PLUMBING"
HDL_TAP"TRUE";
"B \NAC \NWC"3;
"S \NAC"
BN"3"103;
%"TAP"
"1","(-3450,2225)","0","mstr_standard","I231";
;
CDS_LIB"mstr_standard"
BODY_TYPE"PLUMBING"
HDL_TAP"TRUE";
"B \NAC \NWC"3;
"S \NAC"
BN"4"102;
%"TAP"
"1","(-3450,2175)","0","mstr_standard","I232";
;
CDS_LIB"mstr_standard"
BODY_TYPE"PLUMBING"
HDL_TAP"TRUE";
"B \NAC \NWC"3;
"S \NAC"
BN"5"100;
%"TAP"
"1","(-3450,2075)","0","mstr_standard","I233";
;
CDS_LIB"mstr_standard"
BODY_TYPE"PLUMBING"
HDL_TAP"TRUE";
"B \NAC \NWC"3;
"S \NAC"
BN"7"97;
%"TAP"
"1","(-3450,2125)","0","mstr_standard","I234";
;
CDS_LIB"mstr_standard"
BODY_TYPE"PLUMBING"
HDL_TAP"TRUE";
"B \NAC \NWC"3;
"S \NAC"
BN"6"98;
%"TAP"
"1","(-3450,1975)","0","mstr_standard","I236";
;
CDS_LIB"mstr_standard"
BODY_TYPE"PLUMBING"
HDL_TAP"TRUE";
"B \NAC \NWC"4;
"S \NAC"
BN"0"86;
%"TAP"
"1","(-3450,1925)","0","mstr_standard","I237";
;
CDS_LIB"mstr_standard"
BODY_TYPE"PLUMBING"
HDL_TAP"TRUE";
"B \NAC \NWC"4;
"S \NAC"
BN"1"85;
%"TAP"
"1","(-3450,1875)","0","mstr_standard","I238";
;
CDS_LIB"mstr_standard"
BODY_TYPE"PLUMBING"
HDL_TAP"TRUE";
"B \NAC \NWC"4;
"S \NAC"
BN"2"84;
%"TAP"
"1","(-3450,1825)","0","mstr_standard","I239";
;
CDS_LIB"mstr_standard"
BODY_TYPE"PLUMBING"
HDL_TAP"TRUE";
"B \NAC \NWC"4;
"S \NAC"
BN"3"83;
%"TAP"
"1","(-3450,1775)","0","mstr_standard","I240";
;
CDS_LIB"mstr_standard"
BODY_TYPE"PLUMBING"
HDL_TAP"TRUE";
"B \NAC \NWC"4;
"S \NAC"
BN"4"82;
%"TAP"
"1","(-3450,1725)","0","mstr_standard","I241";
;
CDS_LIB"mstr_standard"
BODY_TYPE"PLUMBING"
HDL_TAP"TRUE";
"B \NAC \NWC"4;
"S \NAC"
BN"5"81;
%"TAP"
"1","(-3450,1625)","0","mstr_standard","I242";
;
CDS_LIB"mstr_standard"
BODY_TYPE"PLUMBING"
HDL_TAP"TRUE";
"B \NAC \NWC"4;
"S \NAC"
BN"7"79;
%"TAP"
"1","(-3450,1675)","0","mstr_standard","I243";
;
CDS_LIB"mstr_standard"
BODY_TYPE"PLUMBING"
HDL_TAP"TRUE";
"B \NAC \NWC"4;
"S \NAC"
BN"6"80;
%"TAP"
"1","(-5875,6025)","2","mstr_standard","I244";
;
CDS_LIB"mstr_standard"
BODY_TYPE"PLUMBING"
HDL_TAP"TRUE";
"B \NAC \NWC"5;
"S \NAC"
BN"0"73;
%"TAP"
"1","(-5875,5925)","2","mstr_standard","I245";
;
CDS_LIB"mstr_standard"
BODY_TYPE"PLUMBING"
HDL_TAP"TRUE";
"B \NAC \NWC"5;
"S \NAC"
BN"1"71;
%"TAP"
"1","(-5875,5825)","2","mstr_standard","I246";
;
CDS_LIB"mstr_standard"
BODY_TYPE"PLUMBING"
HDL_TAP"TRUE";
"B \NAC \NWC"5;
"S \NAC"
BN"2"69;
%"TAP"
"1","(-5875,5725)","2","mstr_standard","I247";
;
CDS_LIB"mstr_standard"
BODY_TYPE"PLUMBING"
HDL_TAP"TRUE";
"B \NAC \NWC"5;
"S \NAC"
BN"3"67;
%"TAP"
"1","(-6075,5975)","2","mstr_standard","I248";
;
CDS_LIB"mstr_standard"
BODY_TYPE"PLUMBING"
HDL_TAP"TRUE";
"B \NAC \NWC"9;
"S \NAC"
BN"0"78;
%"TAP"
"1","(-6075,5875)","2","mstr_standard","I249";
;
CDS_LIB"mstr_standard"
BODY_TYPE"PLUMBING"
HDL_TAP"TRUE";
"B \NAC \NWC"9;
"S \NAC"
BN"1"77;
%"TAP"
"1","(-6075,5675)","2","mstr_standard","I250";
;
CDS_LIB"mstr_standard"
BODY_TYPE"PLUMBING"
HDL_TAP"TRUE";
"B \NAC \NWC"9;
"S \NAC"
BN"3"75;
%"TAP"
"1","(-6075,5775)","2","mstr_standard","I251";
;
CDS_LIB"mstr_standard"
BODY_TYPE"PLUMBING"
HDL_TAP"TRUE";
"B \NAC \NWC"9;
"S \NAC"
BN"2"76;
%"TAP"
"1","(-5875,5625)","2","mstr_standard","I252";
;
CDS_LIB"mstr_standard"
BODY_TYPE"PLUMBING"
HDL_TAP"TRUE";
"B \NAC \NWC"5;
"S \NAC"
BN"4"65;
%"TAP"
"1","(-5875,5525)","2","mstr_standard","I253";
;
CDS_LIB"mstr_standard"
BODY_TYPE"PLUMBING"
HDL_TAP"TRUE";
"B \NAC \NWC"5;
"S \NAC"
BN"5"64;
%"TAP"
"1","(-5875,5425)","2","mstr_standard","I254";
;
CDS_LIB"mstr_standard"
BODY_TYPE"PLUMBING"
HDL_TAP"TRUE";
"B \NAC \NWC"5;
"S \NAC"
BN"6"63;
%"TAP"
"1","(-5875,5325)","2","mstr_standard","I255";
;
CDS_LIB"mstr_standard"
BODY_TYPE"PLUMBING"
HDL_TAP"TRUE";
"B \NAC \NWC"5;
"S \NAC"
BN"7"62;
%"TAP"
"1","(-5875,5125)","2","mstr_standard","I256";
;
CDS_LIB"mstr_standard"
BODY_TYPE"PLUMBING"
HDL_TAP"TRUE";
"B \NAC \NWC"5;
"S \NAC"
BN"9"60;
%"TAP"
"1","(-5875,5225)","2","mstr_standard","I257";
;
CDS_LIB"mstr_standard"
BODY_TYPE"PLUMBING"
HDL_TAP"TRUE";
"B \NAC \NWC"5;
"S \NAC"
BN"8"61;
%"TAP"
"1","(-6075,5475)","2","mstr_standard","I258";
;
CDS_LIB"mstr_standard"
BODY_TYPE"PLUMBING"
HDL_TAP"TRUE";
"B \NAC \NWC"9;
"S \NAC"
BN"5"72;
%"TAP"
"1","(-6075,5575)","2","mstr_standard","I259";
;
CDS_LIB"mstr_standard"
BODY_TYPE"PLUMBING"
HDL_TAP"TRUE";
"B \NAC \NWC"9;
"S \NAC"
BN"4"74;
%"TAP"
"1","(-6075,5375)","2","mstr_standard","I260";
;
CDS_LIB"mstr_standard"
BODY_TYPE"PLUMBING"
HDL_TAP"TRUE";
"B \NAC \NWC"9;
"S \NAC"
BN"6"70;
%"TAP"
"1","(-6075,5275)","2","mstr_standard","I261";
;
CDS_LIB"mstr_standard"
BODY_TYPE"PLUMBING"
HDL_TAP"TRUE";
"B \NAC \NWC"9;
"S \NAC"
BN"7"68;
%"TAP"
"1","(-6075,5175)","2","mstr_standard","I262";
;
CDS_LIB"mstr_standard"
BODY_TYPE"PLUMBING"
HDL_TAP"TRUE";
"B \NAC \NWC"9;
"S \NAC"
BN"8"66;
%"TAP"
"1","(-5875,4975)","2","mstr_standard","I263";
;
CDS_LIB"mstr_standard"
BODY_TYPE"PLUMBING"
HDL_TAP"TRUE";
"B \NAC \NWC"6;
"S \NAC"
BN"0"49;
%"TAP"
"1","(-5875,4875)","2","mstr_standard","I264";
;
CDS_LIB"mstr_standard"
BODY_TYPE"PLUMBING"
HDL_TAP"TRUE";
"B \NAC \NWC"6;
"S \NAC"
BN"1"47;
%"TAP"
"1","(-5875,4775)","2","mstr_standard","I265";
;
CDS_LIB"mstr_standard"
BODY_TYPE"PLUMBING"
HDL_TAP"TRUE";
"B \NAC \NWC"6;
"S \NAC"
BN"2"45;
%"TAP"
"1","(-5875,4675)","2","mstr_standard","I266";
;
CDS_LIB"mstr_standard"
BODY_TYPE"PLUMBING"
HDL_TAP"TRUE";
"B \NAC \NWC"6;
"S \NAC"
BN"3"43;
%"TAP"
"1","(-6075,4925)","2","mstr_standard","I267";
;
CDS_LIB"mstr_standard"
BODY_TYPE"PLUMBING"
HDL_TAP"TRUE";
"B \NAC \NWC"10;
"S \NAC"
BN"0"55;
%"TAP"
"1","(-6075,5075)","2","mstr_standard","I268";
;
CDS_LIB"mstr_standard"
BODY_TYPE"PLUMBING"
HDL_TAP"TRUE";
"B \NAC \NWC"9;
"S \NAC"
BN"9"51;
%"TAP"
"1","(-6075,4825)","2","mstr_standard","I269";
;
CDS_LIB"mstr_standard"
BODY_TYPE"PLUMBING"
HDL_TAP"TRUE";
"B \NAC \NWC"10;
"S \NAC"
BN"1"54;
%"TAP"
"1","(-6075,4725)","2","mstr_standard","I270";
;
CDS_LIB"mstr_standard"
BODY_TYPE"PLUMBING"
HDL_TAP"TRUE";
"B \NAC \NWC"10;
"S \NAC"
BN"2"53;
%"TAP"
"1","(-6075,4625)","2","mstr_standard","I271";
;
CDS_LIB"mstr_standard"
BODY_TYPE"PLUMBING"
HDL_TAP"TRUE";
"B \NAC \NWC"10;
"S \NAC"
BN"3"52;
%"TAP"
"1","(-5875,4575)","2","mstr_standard","I272";
;
CDS_LIB"mstr_standard"
BODY_TYPE"PLUMBING"
HDL_TAP"TRUE";
"B \NAC \NWC"6;
"S \NAC"
BN"4"41;
%"TAP"
"1","(-5875,4375)","2","mstr_standard","I273";
;
CDS_LIB"mstr_standard"
BODY_TYPE"PLUMBING"
HDL_TAP"TRUE";
"B \NAC \NWC"6;
"S \NAC"
BN"6"58;
%"TAP"
"1","(-5875,4475)","2","mstr_standard","I274";
;
CDS_LIB"mstr_standard"
BODY_TYPE"PLUMBING"
HDL_TAP"TRUE";
"B \NAC \NWC"6;
"S \NAC"
BN"5"59;
%"TAP"
"1","(-5875,4275)","2","mstr_standard","I275";
;
CDS_LIB"mstr_standard"
BODY_TYPE"PLUMBING"
HDL_TAP"TRUE";
"B \NAC \NWC"6;
"S \NAC"
BN"7"57;
%"TAP"
"1","(-5875,4175)","2","mstr_standard","I276";
;
CDS_LIB"mstr_standard"
BODY_TYPE"PLUMBING"
HDL_TAP"TRUE";
"B \NAC \NWC"6;
"S \NAC"
BN"8"56;
%"TAP"
"1","(-6075,4425)","2","mstr_standard","I277";
;
CDS_LIB"mstr_standard"
BODY_TYPE"PLUMBING"
HDL_TAP"TRUE";
"B \NAC \NWC"10;
"S \NAC"
BN"5"48;
%"TAP"
"1","(-6075,4525)","2","mstr_standard","I278";
;
CDS_LIB"mstr_standard"
BODY_TYPE"PLUMBING"
HDL_TAP"TRUE";
"B \NAC \NWC"10;
"S \NAC"
BN"4"50;
%"TAP"
"1","(-6075,4325)","2","mstr_standard","I279";
;
CDS_LIB"mstr_standard"
BODY_TYPE"PLUMBING"
HDL_TAP"TRUE";
"B \NAC \NWC"10;
"S \NAC"
BN"6"46;
%"TAP"
"1","(-6075,4225)","2","mstr_standard","I280";
;
CDS_LIB"mstr_standard"
BODY_TYPE"PLUMBING"
HDL_TAP"TRUE";
"B \NAC \NWC"10;
"S \NAC"
BN"7"44;
%"TAP"
"1","(-6075,4125)","2","mstr_standard","I281";
;
CDS_LIB"mstr_standard"
BODY_TYPE"PLUMBING"
HDL_TAP"TRUE";
"B \NAC \NWC"10;
"S \NAC"
BN"8"42;
%"TAP"
"1","(-5875,4075)","2","mstr_standard","I286";
;
CDS_LIB"mstr_standard"
BODY_TYPE"PLUMBING"
HDL_TAP"TRUE";
"B \NAC \NWC"6;
"S \NAC"
BN"9"25;
%"TAP"
"1","(-6075,3875)","2","mstr_standard","I287";
;
CDS_LIB"mstr_standard"
BODY_TYPE"PLUMBING"
HDL_TAP"TRUE";
"B \NAC \NWC"7;
"S \NAC"
BN"0"39;
%"TAP"
"1","(-6075,4025)","2","mstr_standard","I288";
;
CDS_LIB"mstr_standard"
BODY_TYPE"PLUMBING"
HDL_TAP"TRUE";
"B \NAC \NWC"10;
"S \NAC"
BN"9"40;
%"TAP"
"1","(-6075,3825)","2","mstr_standard","I289";
;
CDS_LIB"mstr_standard"
BODY_TYPE"PLUMBING"
HDL_TAP"TRUE";
"B \NAC \NWC"7;
"S \NAC"
BN"1"37;
%"TAP"
"1","(-6075,3725)","2","mstr_standard","I290";
;
CDS_LIB"mstr_standard"
BODY_TYPE"PLUMBING"
HDL_TAP"TRUE";
"B \NAC \NWC"7;
"S \NAC"
BN"3"33;
%"TAP"
"1","(-6075,3775)","2","mstr_standard","I291";
;
CDS_LIB"mstr_standard"
BODY_TYPE"PLUMBING"
HDL_TAP"TRUE";
"B \NAC \NWC"7;
"S \NAC"
BN"2"35;
%"TAP"
"1","(-6075,3675)","2","mstr_standard","I292";
;
CDS_LIB"mstr_standard"
BODY_TYPE"PLUMBING"
HDL_TAP"TRUE";
"B \NAC \NWC"7;
"S \NAC"
BN"4"31;
%"TAP"
"1","(-6075,3625)","2","mstr_standard","I293";
;
CDS_LIB"mstr_standard"
BODY_TYPE"PLUMBING"
HDL_TAP"TRUE";
"B \NAC \NWC"7;
"S \NAC"
BN"5"29;
%"TAP"
"1","(-6075,3575)","2","mstr_standard","I294";
;
CDS_LIB"mstr_standard"
BODY_TYPE"PLUMBING"
HDL_TAP"TRUE";
"B \NAC \NWC"7;
"S \NAC"
BN"6"27;
%"TAP"
"1","(-6075,3425)","2","mstr_standard","I295";
;
CDS_LIB"mstr_standard"
BODY_TYPE"PLUMBING"
HDL_TAP"TRUE";
"B \NAC \NWC"8;
"S \NAC"
BN"1"36;
%"TAP"
"1","(-6075,3475)","2","mstr_standard","I296";
;
CDS_LIB"mstr_standard"
BODY_TYPE"PLUMBING"
HDL_TAP"TRUE";
"B \NAC \NWC"8;
"S \NAC"
BN"0"38;
%"TAP"
"1","(-6075,3375)","2","mstr_standard","I297";
;
CDS_LIB"mstr_standard"
BODY_TYPE"PLUMBING"
HDL_TAP"TRUE";
"B \NAC \NWC"8;
"S \NAC"
BN"2"34;
%"TAP"
"1","(-6075,3325)","2","mstr_standard","I298";
;
CDS_LIB"mstr_standard"
BODY_TYPE"PLUMBING"
HDL_TAP"TRUE";
"B \NAC \NWC"8;
"S \NAC"
BN"3"32;
%"TAP"
"1","(-6075,3175)","2","mstr_standard","I299";
;
CDS_LIB"mstr_standard"
BODY_TYPE"PLUMBING"
HDL_TAP"TRUE";
"B \NAC \NWC"8;
"S \NAC"
BN"6"26;
%"TAP"
"1","(-6075,3275)","2","mstr_standard","I300";
;
CDS_LIB"mstr_standard"
BODY_TYPE"PLUMBING"
HDL_TAP"TRUE";
"B \NAC \NWC"8;
"S \NAC"
BN"4"30;
%"TAP"
"1","(-6075,3225)","2","mstr_standard","I301";
;
CDS_LIB"mstr_standard"
BODY_TYPE"PLUMBING"
HDL_TAP"TRUE";
"B \NAC \NWC"8;
"S \NAC"
BN"5"28;
%"Q_RES"
"1","(-6750,2175)","0","pure_quanta","I314";
;
LOCATION"R501"
$SEC"1"
CDS_SEC"1"
TOLERANCE"1%"
VALUE"15   "
PART_NUMBER"CS01502FB11"
PACK_TYPE"0402LF"
CDS_LIB"pure_quanta"
WATTAGE"1/16W"
MATERIAL"CHIP";
"B"
$PN"2"13;
"A"
$PN"1"11;
END.
